Testpoint Report Status for Project:16342-2

Total # of Nets  : 761

Number of nets with "No_Test" property      :   143
Number of nets with testpoints assigned >1  :   12
Number of nets with testpoints assigned =1  :   578
Number of nets with testpoints assigned =0  :   28

Percent (All nets)                              :  77.53%
Percent (All nets Excluded "No_Test" property)  :  95.47%

BMC_ML_PWR_YELLOW_LED                  2
GND                                   15
I2C_IOM_SDA                            2
IOM_FULL_PGOOD                         2
P12V_STBY                              8
P1V2_STBY                              2
P1V8_STBY                              3
P2V5_STBY                              8
P3V3                                   5
P3V3_M2                                8
P3V3_STBY_OUT                          2
TPS74801_P1V2_STBY_OUT                 2

50M_CLK_OE                             1
ADCAV33                                1
ADCVREFFN                              1
ADCVREFFP                              1
ADCVREXT                               1
ADC_12V                                1
ADC_P0V975                             1
ADC_P1V15_STBY                         1
ADC_P1V2_STBY                          1
ADC_P1V5                               1
ADC_P1V8                               1
ADC_P1V8_STBY                          1
ADC_P2V5_STBY                          1
ADC_P3V3                               1
ADC_P3V3_M2                            1
ADC_P3V3_STBY                          1
ADC_P5V_STBY                           1
ADM1278_HS_N                           1
ADM1278_HS_P                           1
AGND_CURRENT_MON                       1
AGND_P1V8_STBY                         1
AGND_P3V3_M2                           1
AGND_P3V3_STBY                         1
AGND_P5V                               1
BMC0_JTAG_RTCK                         1
BMC0_SRST_N                            1
BMC_CPU_DIS                            1
BMC_CPU_EN                             1
BMC_ENTEST                             1
BMC_EXTRST_N                           1
BMC_GPIOS4                             1
BMC_GPIOS5                             1
BMC_GPIOS6                             1
BMC_GPIOS7                             1
BMC_GPIOY0                             1
BMC_GPIOY1                             1
BMC_GPIOY2                             1
BMC_GPIOY3                             1
BMC_GPIOZ4                             1
BMC_GPIOZ5                             1
BMC_GPIOZ6                             1
BMC_GPIOZ7                             1
BMC_LOC_HB                             1
BMC_LOC_HEARTBEAT                      1
BMC_ML_PWR_BLUE_LED                    1
BMC_ML_PWR_BLUE_LED_L                  1
BMC_ML_PWR_BLUE_LED_R                  1
BMC_ML_PWR_YELLOW_LED_R                1
BMC_PEREXT                             1
BMC_RGMII_A4_D3                        1
BMC_RGMII_C2_C3_D1_D2_E6               1
BMC_RMT_HB                             1
BMC_RMT_HEARTBEAT                      1
BMC_SELF_HW_RST                        1
BMC_SELF_HW_RST_D                      1
BMC_SMB10_CLK                          1
BMC_SMB10_DAT                          1
BMC_SMB11_CLK                          1
BMC_SMB11_DAT                          1
BMC_SMB12_CLK                          1
BMC_SMB12_DAT                          1
BMC_SMB13_CLK                          1
BMC_SMB13_DAT                          1
BMC_SMB14_CLK                          1
BMC_SMB14_DAT                          1
BMC_SMB1_CLK                           1
BMC_SMB1_DAT                           1
BMC_SMB2_CLK                           1
BMC_SMB2_CLK_TP                        1
BMC_SMB2_DAT                           1
BMC_SMB2_DAT_TP                        1
BMC_SMB3_CLK                           1
BMC_SMB3_DAT                           1
BMC_SMB4_CLK                           1
BMC_SMB4_DAT                           1
BMC_SMB5_CLK                           1
BMC_SMB5_DAT                           1
BMC_SMB6_CLK                           1
BMC_SMB6_DAT                           1
BMC_SMB7_CLK                           1
BMC_SMB7_DAT                           1
BMC_SMB8_CLK                           1
BMC_SMB8_DAT                           1
BMC_SMB9_CLK                           1
BMC_SMB9_DAT                           1
BMC_TO_EXP_RESET_N                     1
BMC_TO_EXP_RESET_OUT                   1
BMC_TO_EXP_RESET_OUT_R                 1
BMC_TPM_RST_N                          1
BMC_UART_SEL_IN                        1
BMC_UART_SEL_OUT                       1
BOARD_REV_0                            1
BOARD_REV_1                            1
BOARD_REV_2                            1
CFG_SEL0                               1
CFG_SEL1                               1
CLK_50M_BMC_NCSI                       1
COMP_FAST_THROTTLE_N                   1
COMP_POWER_FAIL_N                      1
COMP_POWER_FAIL_R_N                    1
COMP_PWR_BTN_N                         1
COMP_PWR_BTN_R_N                       1
COMP_PWR_EN                            1
COMP_PWR_EN_R                          1
COMP_SPARE_0                           1
COMP_SPARE_0_R                         1
COMP_SPARE_1                           1
COMP_SPARE_1_R                         1
COMP_TO_BMC_RESET                      1
COMP_TO_BMC_RESET_N_OUT                1
COMP_TO_BMC_RESET_R                    1
CONN_A_PRSNTA                          1
CRFILT                                 1
DACAV33                                1
DACRSET                                1
DB_PRSNT_BMC_N                         1
DDR_VREF                               1
DEBUG_CARD_PRSNT                       1
DEBUG_GPIO_BMC_1                       1
DEBUG_GPIO_BMC_2                       1
DEBUG_GPIO_BMC_3                       1
DEBUG_GPIO_BMC_4                       1
DEBUG_GPIO_BMC_5                       1
DEBUG_GPIO_BMC_6                       1
DEBUG_GPIO_BMC_R_1                     1
DEBUG_GPIO_BMC_R_2                     1
DEBUG_GPIO_BMC_R_3                     1
DEBUG_GPIO_BMC_R_4                     1
DEBUG_GPIO_BMC_R_5                     1
DEBUG_GPIO_BMC_R_6                     1
DEBUG_HDR_UART_SEL                     1
DEBUG_RST_BTN_N                        1
DEBUG_RST_BTN_N_R                      1
DEBUG_UART_IOM_RX                      1
DEBUG_UART_IOM_TX                      1
DPB_MISC_ALERT                         1
DPB_MISC_ALERT_OUT                     1
DPB_MISC_ALERT_OUT_R                   1
DPB_MISC_ALERT_O_R                     1
D_FLIP_CLR#                            1
D_FLIP_D                               1
D_FLIP_PRE#                            1
D_FLIP_Q                               1
D_FLIP_Q#                              1
EEPROM_A0                              1
EEPROM_A1                              1
EEPROM_A2                              1
EEPROM_WP                              1
ENCL_FAULT_LED                         1
ENCL_FAULT_LED_R                       1
EXP_SPARE_0                            1
EXP_SPARE_0_R                          1
EXP_SPARE_1                            1
EXP_SPARE_1_R                          1
EXP_UART_EN                            1
EXP_UART_EN_R                          1
FAN_PWM0_BMC                           1
FAN_PWM1_BMC                           1
FM_BMC_RESET_N                         1
FM_TPM_PRSNT_N                         1
FM_TPM_PRSNT_RST                       1
FM_TPM_PRSNT_RST_N                     1
FM_TPM_PRSNT_RST_N_C                   1
FM_TPM_PRSNT_RST_N_R                   1
FP_PWRBTN                              1
FP_PWR_BTN_N                           1
FP_PWR_BTN_N_R                         1
FP_RESET_RC_N                          1
FP_RETBTN                              1
HSW_SCL                                1
HSW_SDA                                1
I2C_BMC_COMP_ALERT_N                   1
I2C_BMC_COMP_ALERT_N_R                 1
I2C_BMC_COMP_SCL                       1
I2C_BMC_COMP_SCL_OUT                   1
I2C_BMC_COMP_SCL_R                     1
I2C_BMC_COMP_SDA                       1
I2C_BMC_COMP_SDA_OUT                   1
I2C_BMC_COMP_SDA_R                     1
I2C_COMP_ALERT_N                       1
I2C_DEBUG_SCL                          1
I2C_DEBUG_SCL_L                        1
I2C_DEBUG_SCL_R                        1
I2C_DEBUG_SDA                          1
I2C_DEBUG_SDA_L                        1
I2C_DEBUG_SDA_R                        1
I2C_DPB_MISC_SCL                       1
I2C_DPB_MISC_SCL_OUT                   1
I2C_DPB_MISC_SCL_R                     1
I2C_DPB_MISC_SDA                       1
I2C_DPB_MISC_SDA_OUT                   1
I2C_DPB_MISC_SDA_R                     1
I2C_DPB_SCL                            1
I2C_DPB_SCL_OUT                        1
I2C_DPB_SCL_R                          1
I2C_DPB_SDA                            1
I2C_DPB_SDA_OUT                        1
I2C_DPB_SDA_R                          1
I2C_EXP_LOC_SCL                        1
I2C_EXP_LOC_SCL_OUT                    1
I2C_EXP_LOC_SCL_R                      1
I2C_EXP_LOC_SDA                        1
I2C_EXP_LOC_SDA_OUT                    1
I2C_EXP_LOC_SDA_R                      1
I2C_EXP_RMT_SCL                        1
I2C_EXP_RMT_SCL_OUT                    1
I2C_EXP_RMT_SCL_R                      1
I2C_EXP_RMT_SDA                        1
I2C_EXP_RMT_SDA_OUT                    1
I2C_EXP_RMT_SDA_R                      1
I2C_IOM_SCL                            1
I2C_M2_1_1V8_SCL                       1
I2C_M2_1_1V8_SDA                       1
I2C_M2_1_SCL                           1
I2C_M2_1_SDA                           1
I2C_M2_2_1V8_SCL                       1
I2C_M2_2_1V8_SDA                       1
I2C_M2_2_SCL                           1
I2C_M2_2_SDA                           1
I2C_MEZZ_ALERT_N                       1
I2C_MEZZ_ALERT_R_N                     1
I2C_MEZZ_FRU_SENSOR_SCL                1
I2C_MEZZ_FRU_SENSOR_SDA                1
I2C_MEZZ_OOB_SCL                       1
I2C_MEZZ_OOB_SDA                       1
I2C_SCC_SCL                            1
I2C_SCC_SCL_OUT                        1
I2C_SCC_SCL_R                          1
I2C_SCC_SDA                            1
I2C_SCC_SDA_OUT                        1
I2C_SCC_SDA_R                          1
I2C_TPM_SCL                            1
I2C_TPM_SDA                            1
IOM_ADM1278_EN                         1
IOM_FULL_PWR_EN                        1
IOM_FULL_PWR_EN_R                      1
IOM_LOC_INS_N                          1
IOM_MATED_N                            1
IOM_STBY_PGOOD                         1
IOM_TYPE0                              1
IOM_TYPE1                              1
IOM_TYPE2                              1
IOM_TYPE3                              1
IO_EXP0_RESET#_FLT                     1
IRQ_CPU_SERIAL                         1
JTAG_BMC_TCK                           1
JTAG_BMC_TDI                           1
JTAG_BMC_TDO                           1
JTAG_BMC_TMS                           1
JTAG_BMC_TRST_N                        1
LED_POSTCODE_0                         1
LED_POSTCODE_1                         1
LED_POSTCODE_2                         1
LED_POSTCODE_3                         1
LED_POSTCODE_4                         1
LED_POSTCODE_5                         1
LED_POSTCODE_6                         1
LED_POSTCODE_7                         1
LPCRST0_N                              1
LPC_CPU_CLKOUT0                        1
LPC_CPU_FRAME_N                        1
M2_1_ACTIVE_N                          1
M2_1_ALERT#                            1
M2_1_ALERT#_R                          1
M2_1_CLKREQ#                           1
M2_1_PRESENT_N                         1
M2_1_PRESENT_N_R                       1
M2_2_ACTIVE_N                          1
M2_2_ALERT#                            1
M2_2_ALERT#_R                          1
M2_2_CLKREQ#                           1
M2_2_PRESENT_N                         1
M2_2_PRESENT_N_R                       1
MAC1_TXD2                              1
MAC1_TXD3                              1
MAC2_TXCTL                             1
MAC2_TXD0                              1
MAC2_TXD1                              1
MAC2_TXD2                              1
MAC2_TXD3                              1
MB0_12V_CTRL_GATE1                     1
MB0_CM_ADR1_R                          1
MB0_CM_ADR2_R                          1
MB0_CM_GATE                            1
MB0_CM_GATE_2                          1
MB0_CM_GATE_R                          1
MB0_CM_OV_R                            1
MB0_CM_SENSE_N                         1
MB0_CM_SENSE_P                         1
MB0_CM_SENSE_R1_N                      1
MB0_CM_SENSE_R1_P                      1
MB0_CM_UV_R                            1
MB0_CM_VOUT_R                          1
MB0_HS_ENABLE                          1
MB0_ISET_R                             1
MB0_ISTART_R                           1
MB0_P12V_MAIN_R                        1
MB0_P12V_PWGIN_R                       1
MB0_PSET_R                             1
MB0_RETRY_R                            1
MB0_SPISS_PD                           1
MB0_TEMP                               1
MB0_TEMP_C                             1
MB0_TEMP_E                             1
MB0_TIME_R                             1
MB0_VCAP_R                             1
MB0_VCC                                1
MEZZA_PRSNT1_N                         1
MEZZ_A_PRSNT_120_N                     1
ML_PWR_BLUE_LED                        1
ML_PWR_BLUE_LED_R                      1
ML_PWR_YELLOW_LED                      1
ML_PWR_YELLOW_LED_R                    1
MPLLAV33                               1
NCSI_RCLK                              1
NCSI_RCLK_R                            1
NCSI_RCSDV                             1
NCSI_RCSDV_R                           1
NCSI_RXD0                              1
NCSI_RXD0_R                            1
NCSI_RXD1                              1
NCSI_RXD1_R                            1
NCSI_RX_ER                             1
NCSI_RX_ER_R                           1
NCSI_TXD0                              1
NCSI_TXD0_R                            1
NCSI_TXD1                              1
NCSI_TXD1_R                            1
NCSI_TXEN                              1
NCSI_TXEN_R                            1
P12V_A_PGOOD                           1
P12V_A_PGOOD_R                         1
P12V_IOM                               1
P12V_IOM_PGOOD                         1
P12V_STBY_VCC_PU4                      1
P12V_STBY_VDD_PU2                      1
P12V_STBY_VDD_U81                      1
P12V_STBY_VIN_PU1                      1
P12V_STBY_VIN_PU2                      1
P12V_STBY_VIN_PU4                      1
P12V_STBY_VIN_U81                      1
P1V15_STBY                             1
P1V15_STBY_PG                          1
P1V15_STBY_PG_G                        1
P1V8_STBY_CC                           1
P1V8_STBY_CC_R                         1
P1V8_STBY_EN_R                         1
P1V8_STBY_SNB                          1
P1V8_STBY_SS                           1
P1V8_STBY_SW                           1
P1V8_STBY_VBST                         1
P1V8_STBY_VBST_RR                      1
P1V8_STBY_VFB                          1
P1V8_STBY_VFB_R                        1
P1V8_STBY_VO                           1
P1V8_STBY_VRG5                         1
P3V3_EN                                1
P3V3_EN_R                              1
P3V3_M2_EN                             1
P3V3_M2_LL                             1
P3V3_M2_LL_R                           1
P3V3_M2_MODE                           1
P3V3_M2_RF                             1
P3V3_M2_SNB                            1
P3V3_M2_TRIP                           1
P3V3_M2_VBST                           1
P3V3_M2_VBST_RC                        1
P3V3_M2_VFB                            1
P3V3_M2_VFB_R                          1
P3V3_M2_VREG                           1
P3V3_PG                                1
P3V3_SNB                               1
P3V3_STBY                              1
P3V3_STBY_EN                           1
P3V3_STBY_LL                           1
P3V3_STBY_LL_R                         1
P3V3_STBY_MODE                         1
P3V3_STBY_RF                           1
P3V3_STBY_TRIP                         1
P3V3_STBY_VFB                          1
P3V3_STBY_VREG                         1
P3V3_VBST                              1
P3V3_VBST_RC                           1
P5V_CC                                 1
P5V_EN_R                               1
P5V_LL                                 1
P5V_LL_R                               1
P5V_MODE                               1
P5V_RF                                 1
P5V_SNB                                1
P5V_STBY                               1
P5V_STBY_VREG                          1
P5V_TRIP                               1
P5V_USB                                1
P5V_VBST                               1
P5V_VBST_RC                            1
P5V_VBUS_CONN                          1
P5V_VDD                                1
P5V_VFB                                1
P5V_VFB_R                              1
PCIE_COMP_TO_IOM_RST_2                 1
PCIE_COMP_TO_IOM_RST_3                 1
PCIE_COMP_TO_IOM_RST_4                 1
PCIE_COMP_TO_IOM_RST_4_R               1
PCIE_RST_R_N                           1
PCIE_WAKE_N                            1
PD_PERST_N                             1
PD_USB2AVRES                           1
PD_USB2BVRES                           1
PECI                                   1
PLLFILT                                1
PQ2_D                                  1
PQ2_G                                  1
PWM_OUT_ZONE_C                         1
PWM_OUT_ZONE_D                         1
PWRBTN_OUT_N                           1
PWRBTN_OUT_N_R                         1
PWRGD_P1V2_STBY                        1
PWRGD_P1V8_STBY                        1
PWRGD_P2V5_STBY                        1
PWRGD_P3V3_STBY                        1
PWRGD_P3V3_STBY_N                      1
PWRGD_P3V3_STBY_N_R1                   1
PWRGD_P3V3_STBY_N_R2                   1
PWRGD_P5V_STBY                         1
PWR_BTN_GND                            1
Q20_G                                  1
Q21_G                                  1
Q4_G                                   1
RMII_BMC_MDC_R                         1
RMII_BMC_MDIO_R                        1
RSTBTN_OUT_N                           1
RSTBTN_OUT_N_R                         1
RST_BMC_EXTRST_N                       1
RST_BMC_EXTRST_N_1                     1
RST_BTN_GND                            1
SCC_A_HB_IN_R                          1
SCC_B_HB_IN_R                          1
SCC_LOC_FULLPWR_EN                     1
SCC_LOC_FULL_PWR_EN                    1
SCC_LOC_HEARTBEAT                      1
SCC_PWR_EN_R                           1
SCC_RMT_FULLPWR_EN                     1
SCC_RMT_FULL_PWR_EN                    1
SCC_RMT_HEARTBEAT                      1
SCC_RMT_TYPE_0                         1
SCC_RMT_TYPE_0_R                       1
SCC_STBY_PWR_EN                        1
SLOTID_0                               1
SLOTID_1                               1
SYS_PWR_LED                            1
SYS_RESET_N                            1
SYS_RESET_N_OUT                        1
SYS_RESET_N_OUT_R                      1
SYS_RST_BTN_IN_N                       1
SYS_RST_EN                             1
TCA9555_A0                             1
TCA9555_A1                             1
TCA9555_A2                             1
TEMP_1_A0                              1
TEMP_1_A1                              1
TEMP_1_A2                              1
TEMP_1_ALERT                           1
TEMP_1_SCL                             1
TEMP_1_SDA                             1
TEMP_2_A0                              1
TEMP_2_A1                              1
TEMP_2_A2                              1
TEMP_2_ALERT                           1
TEMP_2_SCL                             1
TEMP_2_SDA                             1
TEMP_3_A0                              1
TEMP_3_A1                              1
TEMP_3_A2                              1
TEMP_3_ALERT                           1
TEMP_3_SCL                             1
TEMP_3_SDA                             1
THROTTLE_N                             1
TPM_PRSNT_N_R                          1
TPS74801_P1V15_STBY_BIAS               1
TPS74801_P1V15_STBY_EN                 1
TPS74801_P1V15_STBY_FB                 1
TPS74801_P1V15_STBY_OUT                1
TPS74801_P1V15_STBY_SS                 1
TPS74801_P1V2_STBY_BIAS                1
TPS74801_P1V2_STBY_EN                  1
TPS74801_P1V2_STBY_FB                  1
TPS74801_P1V2_STBY_SS                  1
TPS74801_P2V5_STBY_BIAS                1
TPS74801_P2V5_STBY_EN                  1
TPS74801_P2V5_STBY_FB                  1
TPS74801_P2V5_STBY_OUT                 1
TPS74801_P2V5_STBY_SS                  1
TP_BMC0_LPC_LAD0                       1
TP_BMC0_LPC_LAD1                       1
TP_BMC0_LPC_LAD2                       1
TP_BMC0_LPC_LAD3                       1
TP_BMC_EXT1_LED_B                      1
TP_BMC_EXT1_LED_G                      1
TP_BMC_EXT2_LED_B                      1
TP_BMC_EXT2_LED_G                      1
TP_BMC_GPIOA0                          1
TP_BMC_GPIOA6                          1
TP_BMC_GPIOA7                          1
TP_BMC_GPIOI0                          1
TP_BMC_GPIOI1                          1
TP_BMC_GPIOI2                          1
TP_BMC_GPIOI3                          1
TP_BMC_GPIOI4                          1
TP_BMC_GPIOI5                          1
TP_BMC_GPIOI6                          1
TP_BMC_GPIOI7                          1
TP_BMC_GPIOL0                          1
TP_BMC_GPIOL1                          1
TP_BMC_GPIOL2                          1
TP_BMC_GPIOL3                          1
TP_BMC_GPIOL4                          1
TP_BMC_GPIOL5                          1
TP_BMC_GPION2                          1
TP_BMC_GPION3                          1
TP_BMC_GPION4                          1
TP_BMC_GPION5                          1
TP_BMC_GPION6                          1
TP_BMC_GPION7                          1
TP_BMC_GPIOR1                          1
TP_BMC_GPIOR2                          1
TP_BMC_GPIOR3                          1
TP_BMC_GPIOR4                          1
TP_BMC_GPIOR5                          1
TP_BMC_GPIOT0                          1
TP_BMC_GPIOT6                          1
TP_M2_1_MFG_CLK                        1
TP_M2_1_MFG_DAT                        1
TP_M2_2_MFG_CLK                        1
TP_M2_2_MFG_DAT                        1
TP_USB_SDA                             1
U30_Q1                                 1
U82_VREF2                              1
U83_VREF2                              1
UART_BMC_COMP_IN_RX                    1
UART_BMC_COMP_IN_RX_R                  1
UART_BMC_RX                            1
UART_BMC_R_RX                          1
UART_BMC_R_TX                          1
UART_BMC_TX                            1
UART_COMP_IN_RX                        1
UART_COMP_IN_RX_AND                    1
UART_COMP_IN_R_RX                      1
UART_COMP_OUT_TX                       1
UART_COMP_OUT_TX_R                     1
UART_COMP_RX                           1
UART_COMP_R_TX                         1
UART_COMP_TX                           1
UART_EXP_BMC_RX                        1
UART_EXP_BMC_RX_R                      1
UART_EXP_BMC_TX                        1
UART_EXP_BMC_TX_R                      1
UART_IOM_RX                            1
UART_IOM_TX                            1
UART_SDB_RX                            1
UART_SDB_TX                            1
UART_SDB_TX_R                          1
UART_SEL_MUX                           1
USB_CONN_GND                           1
USB_EN_1                               1
USB_EN_2                               1
USB_EN_3                               1
USB_EN_4                               1
USB_OCS_N1                             1
USB_OCS_N2                             1
USB_OCS_N3                             1
USB_OCS_N4                             1
USB_RESET_N                            1
USB_SUSP_IND                           1
V1PLLAV11                              1
VBUS_DET                               1
VPLLAV33                               1
VREF_2V2                               1

50M_CLK_OUT                            0
50M_CLK_OUT_R                          0
BMC_HBLED                              0
BMC_HBLED_R                            0
CLKIN_24M_BMC                          0
FM_OSC_50M_EN                          0
OSC_OE                                 0
OSC_OUT                                0
P3V3_STBY_ROVP                         0
P3V3_STBY_VFB_R                        0
PU_IBMC_BT_HOLD_N                      0
RBIAS                                  0
U104_EN                                0
UART_COMP_IN_RX_AND_R                  0
UART_COMP_R_RX                         0
USB_COMP_DN                            0
USB_COMP_DP                            0
USB_HUB_XTAL_IN                        0
USB_HUB_XTAL_OUT                       0
USB_P1_DN                              0
USB_P1_DP                              0
USB_P1_F_DN1                           0
USB_P1_F_DP1                           0
USB_P2_DN                              0
USB_P2_DP                              0
USB_P3_DN                              0
USB_P3_DP                              0
WP_ENABLE                              0
